FILE_TYPE = MACRO_DRAWING;
SET COLOR_WIRE YELLOW;
SET COLOR_PROP ORANGE;
SET COLOR_DOT WHITE;
SET COLOR_ARC YELLOW;
SET COLOR_BODY GREEN;
SET COLOR_NOTE PURPLE;
SET PROP_DISPLAY VALUE;
SET PAGE_NUMBER P397;
FORCEADD QUANTA_TITLE_BLOCK_C..1
(0 0);
FORCEPROP 1 LAST CUSTOM_TXT_CDS <NAME_2>
J 0
(-3175 50);
FORCEPROP 1 LAST CUSTOM_TXT_CDS <NAME_1>
J 0
(-3175 175);
FORCEPROP 1 LAST CUSTOM_TXT_CDS <Q_NUMBER>
J 0
(-1403 103);
DISPLAY 1.212766 (-1403 103);
FORCEPROP 1 LAST CUSTOM_TXT_CDS <Q_PROJ>
J 0
(-2382 102);
DISPLAY 1.212766 (-2382 102);
FORCEPROP 1 LAST CUSTOM_TXT_CDS <Q_REV>
J 0
(-184 103);
DISPLAY 1.212766 (-184 103);
FORCEPROP 1 LAST CUSTOM_TXT_CDS <CON_LAST_MODIFIED>
J 0
(-1885 15);
DISPLAY 0.978723 (-1885 15);
FORCEPROP 1 LAST CUSTOM_TXT_CDS <CON_PAGE_NUM> OF <CON_TOTAL_PAGES>
J 0
(-446 18);
DISPLAY 0.978723 (-446 18);
FORCEPROP 1 LAST Q_TITLE BLANK
J 0
(-9366 26);
DISPLAY 2.446809 (-9366 26);
PAINT GREEN (-9366 26);
FORCEPROP 2 LAST CDS_LIB pure_quanta
J 0
(0 0);
DISPLAY INVISIBLE (0 0);
FORCEPROP 1 LAST CDS_LMAN_SYM_OUTLINE -9475,6775,100,-125
J 0
(0 0);
DISPLAY 0.468085 (0 0);
PAINT GREEN (0 0);
DISPLAY INVISIBLE (0 0);
FORCEPROP 2 LAST PAGE_BORDER TRUE
J 0
(-7890 5250);
DISPLAY 0.638298 (-7890 5250);
PAINT PINK (-7890 5250);
DISPLAY INVISIBLE (-7890 5250);
FORCEPROP 2 LAST CDS_XR_PAGE_TITLE CR-327 : @T6G_MB_LIB.T6G(SCH_1):PAGE327
J 0
(-7890 5250);
DISPLAY 0.638298 (-7890 5250);
PAINT PINK (-7890 5250);
DISPLAY INVISIBLE (-7890 5250);
FORCEPROP 2 LAST CUSTOM_TXT_CDS <XR_PAGE_TITLE>
J 0
(-7890 5250);
DISPLAY 0.638298 (-7890 5250);
PAINT PINK (-7890 5250);
DISPLAY INVISIBLE (-7890 5250);
FORCEPROP 1 LAST COMMENT_BODY TRUE
J 0
(12 -13);
DISPLAY 0.978723 (12 -13);
PAINT GREEN (12 -13);
DISPLAY INVISIBLE (12 -13);
FORCEPROP 1 LAST Q_DEPT BU9
J 1
(-3763 49);
DISPLAY 1.957447 (-3763 49);
PAINT GREEN (-3763 49);
DISPLAY INVISIBLE (-3763 49);
FORCEPROP 0 LAST CDS_CON_LAST_MODIFIED Thu Aug 24 10:16:46 2023
J 0
(-1885 15);
DISPLAY INVISIBLE (-1885 15);
QUIT
